(kicad_pcb
	(version 20260206)
	(generator "pcbnew")
	(generator_version "10.0")
	(general
		(thickness 1.6)
		(legacy_teardrops no)
	)
	(paper "A4")
	(title_block
		(title "Wiwynn_Tioga_Pass_MB.brd")
		(comment 1 "Tioga Pass / footprints 1894-1894 of 4770")
	)
	(layers
		(0 "F.Cu" signal "TOP")
		(4 "In1.Cu" signal "L2GND")
		(6 "In2.Cu" signal "L3")
		(8 "In3.Cu" signal "L4GND")
		(10 "In4.Cu" signal "L5")
		(12 "In5.Cu" signal "L6GND")
		(14 "In6.Cu" signal "L7VCC")
		(16 "In7.Cu" signal "L8VCC")
		(18 "In8.Cu" signal "L9GND")
		(20 "In9.Cu" signal "L10")
		(22 "In10.Cu" signal "L11GND")
		(24 "In11.Cu" signal "L12")
		(26 "In12.Cu" signal "L13GND")
		(2 "B.Cu" signal "BOTTOM")
		(9 "F.Adhes" user "F.Adhesive")
		(11 "B.Adhes" user "B.Adhesive")
		(13 "F.Paste" user "Package Geometry/Pastemask Top")
		(15 "B.Paste" user "Package Geometry/Pastemask Bottom")
		(5 "F.SilkS" user "Ref Des/Silkscreen Top")
		(7 "B.SilkS" user "Ref Des/Silkscreen Bottom")
		(1 "F.Mask" user "Board Geometry/Soldermask Top")
		(3 "B.Mask" user "Board Geometry/Soldermask Bottom")
		(17 "Dwgs.User" user "User.Drawings")
		(19 "Cmts.User" user "User.Comments")
		(21 "Eco1.User" user "User.Eco1")
		(23 "Eco2.User" user "User.Eco2")
		(25 "Edge.Cuts" user "Board Geometry/Outline")
		(27 "Margin" user)
		(31 "F.CrtYd" user "Package Geometry/Place Bound Top")
		(29 "B.CrtYd" user "Package Geometry/Place Bound Bottom")
		(35 "F.Fab" user "Ref Des/Assembly Top")
		(33 "B.Fab" user "Ref Des/Assembly Bottom")
	)
	(footprint ""
		(layer "F.Cu")
		(at 400.685 -76.073)
		(property "Reference" "C8E3"
			(at 0 0 0)
			(layer "F.SilkS")
			(hide yes)
			(effects
				(font
					(size 1.27 1.27)
				)
			)
		)
		(property "Value" ""
			(at 0 0 0)
			(layer "F.Fab")
			(effects
				(font
					(size 1.27 1.27)
				)
			)
		)
		(duplicate_pad_numbers_are_jumpers no)
		(fp_poly
			(pts
				(xy 0.3048 -0.1016) (xy 0.3048 0.9906) (xy -0.3048 0.9906) (xy -0.3048 -0.1016)
			)
			(stroke
				(width 0)
				(type default)
			)
			(fill no)
			(layer "F.CrtYd")
		)
		(fp_line
			(start -0.3048 -0.1016)
			(end -0.3048 0.9906)
			(stroke
				(width 0.1)
				(type default)
			)
			(layer "F.Fab")
		)
		(fp_line
			(start -0.3048 0.9906)
			(end 0.3048 0.9906)
			(stroke
				(width 0.1)
				(type default)
			)
			(layer "F.Fab")
		)
		(fp_line
			(start 0.3048 -0.1016)
			(end -0.3048 -0.1016)
			(stroke
				(width 0.1)
				(type default)
			)
			(layer "F.Fab")
		)
		(fp_line
			(start 0.3048 0.9906)
			(end 0.3048 -0.1016)
			(stroke
				(width 0.1)
				(type default)
			)
			(layer "F.Fab")
		)
		(pad "1" smd rect
			(at 0 0)
			(size 0.508 0.508)
			(layers "F.Cu" "F.Mask" "F.Paste")
			(net "PWRGD_P12V_HSC")
		)
		(pad "2" smd rect
			(at 0 0.889)
			(size 0.508 0.508)
			(layers "F.Cu" "F.Mask" "F.Paste")
			(net "GND")
		)
		(zone
			(layer "F.Cu")
			(hatch none 0.5)
			(connect_pads
				(clearance 0)
			)
			(min_thickness 0.25)
			(keepout
				(tracks allowed)
				(vias not_allowed)
				(pads allowed)
				(copperpour not_allowed)
				(footprints allowed)
			)
			(placement
				(enabled no)
				(sheetname "")
			)
			(fill
				(thermal_gap 0.5)
				(thermal_bridge_width 0.5)
				(island_removal_mode 0)
			)
			(polygon
				(pts
					(xy 400.431 -75.819) (xy 400.939 -75.819) (xy 400.939 -75.438) (xy 400.431 -75.438)
				)
			)
		)
		(zone
			(layer "F.Cu")
			(hatch none 0.5)
			(connect_pads
				(clearance 0)
			)
			(min_thickness 0.25)
			(keepout
				(tracks not_allowed)
				(vias allowed)
				(pads allowed)
				(copperpour not_allowed)
				(footprints allowed)
			)
			(placement
				(enabled no)
				(sheetname "")
			)
			(fill
				(thermal_gap 0.5)
				(thermal_bridge_width 0.5)
				(island_removal_mode 0)
			)
			(polygon
				(pts
					(xy 400.431 -75.438) (xy 400.939 -75.438) (xy 400.939 -75.819) (xy 400.431 -75.819)
				)
			)
		)
	)
)
